(kicad_pcb
	(version 20260206)
	(generator "pcbnew")
	(generator_version "10.0")
	(general
		(thickness 1.6)
		(legacy_teardrops no)
	)
	(paper "A4")
	(title_block
		(title "04192023_DAF0TMB3IC0_F0TG_MB_C_brd_V02_OCP.brd")
		(comment 1 "Grand Teton / footprints 1986-1991 of 8354")
	)
	(layers
		(0 "F.Cu" signal "TOP")
		(4 "In1.Cu" signal "GND")
		(6 "In2.Cu" signal "IN1")
		(8 "In3.Cu" signal "GND1")
		(10 "In4.Cu" signal "IN2")
		(12 "In5.Cu" signal "GND2")
		(14 "In6.Cu" signal "IN3")
		(16 "In7.Cu" signal "GND3")
		(18 "In8.Cu" signal "VCC")
		(20 "In9.Cu" signal "VCC1")
		(22 "In10.Cu" signal "GND4")
		(24 "In11.Cu" signal "IN4")
		(26 "In12.Cu" signal "GND5")
		(28 "In13.Cu" signal "IN5")
		(30 "In14.Cu" signal "GND6")
		(32 "In15.Cu" signal "IN6")
		(34 "In16.Cu" signal "GND7")
		(2 "B.Cu" signal "BOTTOM")
		(9 "F.Adhes" user "F.Adhesive")
		(11 "B.Adhes" user "B.Adhesive")
		(13 "F.Paste" user "Package Geometry/Pastemask Top")
		(15 "B.Paste" user "Package Geometry/Pastemask Bottom")
		(5 "F.SilkS" user "Ref Des/Silkscreen Top")
		(7 "B.SilkS" user "Ref Des/Silkscreen Bottom")
		(1 "F.Mask" user "Board Geometry/Soldermask Top")
		(3 "B.Mask" user "Board Geometry/Soldermask Bottom")
		(17 "Dwgs.User" user "User.Drawings")
		(19 "Cmts.User" user "User.Comments")
		(21 "Eco1.User" user "User.Eco1")
		(23 "Eco2.User" user "User.Eco2")
		(25 "Edge.Cuts" user "Board Geometry/Outline")
		(27 "Margin" user)
		(31 "F.CrtYd" user "Package Geometry/Place Bound Top")
		(29 "B.CrtYd" user "Package Geometry/Place Bound Bottom")
		(35 "F.Fab" user "Ref Des/Assembly Top")
		(33 "B.Fab" user "Ref Des/Assembly Bottom")
	)
	(footprint ""
		(layer "F.Cu")
		(at 303.353978 -13.41501)
		(property "Reference" "R4189"
			(at 0 0 0)
			(layer "F.SilkS")
			(hide yes)
			(effects
				(font
					(size 1.27 1.27)
				)
			)
		)
		(property "Value" ""
			(at 0 0 0)
			(layer "F.Fab")
			(effects
				(font
					(size 1.27 1.27)
				)
			)
		)
		(duplicate_pad_numbers_are_jumpers no)
		(fp_line
			(start -0.7874 -0.4064)
			(end 0.7874 -0.4064)
			(stroke
				(width 0.1524)
				(type default)
			)
			(layer "F.SilkS")
		)
		(fp_line
			(start -0.7874 0.4064)
			(end -0.7874 -0.4064)
			(stroke
				(width 0.1524)
				(type default)
			)
			(layer "F.SilkS")
		)
		(fp_line
			(start 0.7874 -0.4064)
			(end 0.7874 0.4064)
			(stroke
				(width 0.1524)
				(type default)
			)
			(layer "F.SilkS")
		)
		(fp_line
			(start 0.7874 0.4064)
			(end -0.7874 0.4064)
			(stroke
				(width 0.1524)
				(type default)
			)
			(layer "F.SilkS")
		)
		(fp_line
			(start -0.67945 -0.305054)
			(end -0.12065 -0.305054)
			(stroke
				(width 0.1)
				(type default)
			)
			(layer "F.Fab")
		)
		(fp_line
			(start -0.67945 0.3048)
			(end -0.67945 -0.305054)
			(stroke
				(width 0.1)
				(type default)
			)
			(layer "F.Fab")
		)
		(fp_line
			(start -0.12065 -0.305054)
			(end -0.12065 -0.2794)
			(stroke
				(width 0.1)
				(type default)
			)
			(layer "F.Fab")
		)
		(fp_line
			(start -0.12065 -0.2794)
			(end 0.12065 -0.2794)
			(stroke
				(width 0.1)
				(type default)
			)
			(layer "F.Fab")
		)
		(fp_line
			(start -0.12065 0.2794)
			(end -0.12065 0.3048)
			(stroke
				(width 0.1)
				(type default)
			)
			(layer "F.Fab")
		)
		(fp_line
			(start -0.12065 0.3048)
			(end -0.67945 0.3048)
			(stroke
				(width 0.1)
				(type default)
			)
			(layer "F.Fab")
		)
		(fp_line
			(start 0.120396 0.2794)
			(end -0.12065 0.2794)
			(stroke
				(width 0.1)
				(type default)
			)
			(layer "F.Fab")
		)
		(fp_line
			(start 0.120396 0.3048)
			(end 0.120396 0.2794)
			(stroke
				(width 0.1)
				(type default)
			)
			(layer "F.Fab")
		)
		(fp_line
			(start 0.12065 -0.3048)
			(end 0.67945 -0.3048)
			(stroke
				(width 0.1)
				(type default)
			)
			(layer "F.Fab")
		)
		(fp_line
			(start 0.12065 -0.2794)
			(end 0.12065 -0.3048)
			(stroke
				(width 0.1)
				(type default)
			)
			(layer "F.Fab")
		)
		(fp_line
			(start 0.67945 -0.3048)
			(end 0.67945 0.3048)
			(stroke
				(width 0.1)
				(type default)
			)
			(layer "F.Fab")
		)
		(fp_line
			(start 0.67945 0.3048)
			(end 0.120396 0.3048)
			(stroke
				(width 0.1)
				(type default)
			)
			(layer "F.Fab")
		)
		(pad "1" smd circle
			(at -0.40005 0)
			(size 0 0)
			(layers "F.Cu" "F.Mask" "F.Paste")
			(net "U271_1_ADD2")
		)
		(pad "2" smd circle
			(at 0.40005 0)
			(size 0 0)
			(layers "F.Cu" "F.Mask" "F.Paste")
			(net "GND")
		)
	)
	(footprint ""
		(layer "F.Cu")
		(at 66.0654 -39.487348 90)
		(property "Reference" "R3827"
			(at 0 0 90)
			(layer "F.SilkS")
			(hide yes)
			(effects
				(font
					(size 1.27 1.27)
				)
			)
		)
		(property "Value" ""
			(at 0 0 90)
			(layer "F.Fab")
			(effects
				(font
					(size 1.27 1.27)
				)
			)
		)
		(duplicate_pad_numbers_are_jumpers no)
		(fp_line
			(start 0.7874 -0.4064)
			(end 0.7874 0.4064)
			(stroke
				(width 0.1524)
				(type default)
			)
			(layer "F.SilkS")
		)
		(fp_line
			(start -0.7874 -0.4064)
			(end 0.7874 -0.4064)
			(stroke
				(width 0.1524)
				(type default)
			)
			(layer "F.SilkS")
		)
		(fp_line
			(start 0.7874 0.4064)
			(end -0.7874 0.4064)
			(stroke
				(width 0.1524)
				(type default)
			)
			(layer "F.SilkS")
		)
		(fp_line
			(start -0.7874 0.4064)
			(end -0.7874 -0.4064)
			(stroke
				(width 0.1524)
				(type default)
			)
			(layer "F.SilkS")
		)
		(fp_line
			(start -0.12065 -0.305054)
			(end -0.12065 -0.2794)
			(stroke
				(width 0.1)
				(type default)
			)
			(layer "F.Fab")
		)
		(fp_line
			(start -0.67945 -0.305054)
			(end -0.12065 -0.305054)
			(stroke
				(width 0.1)
				(type default)
			)
			(layer "F.Fab")
		)
		(fp_line
			(start 0.67945 -0.3048)
			(end 0.67945 0.3048)
			(stroke
				(width 0.1)
				(type default)
			)
			(layer "F.Fab")
		)
		(fp_line
			(start 0.12065 -0.3048)
			(end 0.67945 -0.3048)
			(stroke
				(width 0.1)
				(type default)
			)
			(layer "F.Fab")
		)
		(fp_line
			(start 0.12065 -0.2794)
			(end 0.12065 -0.3048)
			(stroke
				(width 0.1)
				(type default)
			)
			(layer "F.Fab")
		)
		(fp_line
			(start -0.12065 -0.2794)
			(end 0.12065 -0.2794)
			(stroke
				(width 0.1)
				(type default)
			)
			(layer "F.Fab")
		)
		(fp_line
			(start 0.120396 0.2794)
			(end -0.12065 0.2794)
			(stroke
				(width 0.1)
				(type default)
			)
			(layer "F.Fab")
		)
		(fp_line
			(start -0.12065 0.2794)
			(end -0.12065 0.3048)
			(stroke
				(width 0.1)
				(type default)
			)
			(layer "F.Fab")
		)
		(fp_line
			(start 0.67945 0.3048)
			(end 0.120396 0.3048)
			(stroke
				(width 0.1)
				(type default)
			)
			(layer "F.Fab")
		)
		(fp_line
			(start 0.120396 0.3048)
			(end 0.120396 0.2794)
			(stroke
				(width 0.1)
				(type default)
			)
			(layer "F.Fab")
		)
		(fp_line
			(start -0.12065 0.3048)
			(end -0.67945 0.3048)
			(stroke
				(width 0.1)
				(type default)
			)
			(layer "F.Fab")
		)
		(fp_line
			(start -0.67945 0.3048)
			(end -0.67945 -0.305054)
			(stroke
				(width 0.1)
				(type default)
			)
			(layer "F.Fab")
		)
		(pad "1" smd circle
			(at -0.40005 0 90)
			(size 0 0)
			(layers "F.Cu" "F.Mask" "F.Paste")
			(net "P12V_OCP_UV_2_R")
		)
		(pad "2" smd circle
			(at 0.40005 0 90)
			(size 0 0)
			(layers "F.Cu" "F.Mask" "F.Paste")
			(net "P12V_OCP_UV_2")
		)
	)
	(footprint ""
		(layer "F.Cu")
		(at 197.523608 -105.497376 180)
		(property "Reference" "R1185"
			(at 0 0 180)
			(layer "F.SilkS")
			(hide yes)
			(effects
				(font
					(size 1.27 1.27)
				)
			)
		)
		(property "Value" ""
			(at 0 0 180)
			(layer "F.Fab")
			(effects
				(font
					(size 1.27 1.27)
				)
			)
		)
		(duplicate_pad_numbers_are_jumpers no)
		(fp_line
			(start 0.7874 0.4064)
			(end -0.7874 0.4064)
			(stroke
				(width 0.1524)
				(type default)
			)
			(layer "F.SilkS")
		)
		(fp_line
			(start 0.7874 -0.4064)
			(end 0.7874 0.4064)
			(stroke
				(width 0.1524)
				(type default)
			)
			(layer "F.SilkS")
		)
		(fp_line
			(start -0.7874 0.4064)
			(end -0.7874 -0.4064)
			(stroke
				(width 0.1524)
				(type default)
			)
			(layer "F.SilkS")
		)
		(fp_line
			(start -0.7874 -0.4064)
			(end 0.7874 -0.4064)
			(stroke
				(width 0.1524)
				(type default)
			)
			(layer "F.SilkS")
		)
		(fp_line
			(start 0.67945 0.3048)
			(end 0.120396 0.3048)
			(stroke
				(width 0.1)
				(type default)
			)
			(layer "F.Fab")
		)
		(fp_line
			(start 0.67945 -0.3048)
			(end 0.67945 0.3048)
			(stroke
				(width 0.1)
				(type default)
			)
			(layer "F.Fab")
		)
		(fp_line
			(start 0.12065 -0.2794)
			(end 0.12065 -0.3048)
			(stroke
				(width 0.1)
				(type default)
			)
			(layer "F.Fab")
		)
		(fp_line
			(start 0.12065 -0.3048)
			(end 0.67945 -0.3048)
			(stroke
				(width 0.1)
				(type default)
			)
			(layer "F.Fab")
		)
		(fp_line
			(start 0.120396 0.3048)
			(end 0.120396 0.2794)
			(stroke
				(width 0.1)
				(type default)
			)
			(layer "F.Fab")
		)
		(fp_line
			(start 0.120396 0.2794)
			(end -0.12065 0.2794)
			(stroke
				(width 0.1)
				(type default)
			)
			(layer "F.Fab")
		)
		(fp_line
			(start -0.12065 0.3048)
			(end -0.67945 0.3048)
			(stroke
				(width 0.1)
				(type default)
			)
			(layer "F.Fab")
		)
		(fp_line
			(start -0.12065 0.2794)
			(end -0.12065 0.3048)
			(stroke
				(width 0.1)
				(type default)
			)
			(layer "F.Fab")
		)
		(fp_line
			(start -0.12065 -0.2794)
			(end 0.12065 -0.2794)
			(stroke
				(width 0.1)
				(type default)
			)
			(layer "F.Fab")
		)
		(fp_line
			(start -0.12065 -0.305054)
			(end -0.12065 -0.2794)
			(stroke
				(width 0.1)
				(type default)
			)
			(layer "F.Fab")
		)
		(fp_line
			(start -0.67945 0.3048)
			(end -0.67945 -0.305054)
			(stroke
				(width 0.1)
				(type default)
			)
			(layer "F.Fab")
		)
		(fp_line
			(start -0.67945 -0.305054)
			(end -0.12065 -0.305054)
			(stroke
				(width 0.1)
				(type default)
			)
			(layer "F.Fab")
		)
		(pad "1" smd circle
			(at -0.40005 0 180)
			(size 0 0)
			(layers "F.Cu" "F.Mask" "F.Paste")
			(net "PVDDCR_CPU0_P0_PMALERT")
		)
		(pad "2" smd circle
			(at 0.40005 0 180)
			(size 0 0)
			(layers "F.Cu" "F.Mask" "F.Paste")
			(net "P3V3_AUX")
		)
	)
	(footprint ""
		(layer "F.Cu")
		(at 187.280296 -133.477762 -90)
		(property "Reference" "R6792"
			(at 0 0 270)
			(layer "F.SilkS")
			(hide yes)
			(effects
				(font
					(size 1.27 1.27)
				)
			)
		)
		(property "Value" ""
			(at 0 0 270)
			(layer "F.Fab")
			(effects
				(font
					(size 1.27 1.27)
				)
			)
		)
		(duplicate_pad_numbers_are_jumpers no)
		(fp_line
			(start -0.7874 0.4064)
			(end -0.7874 -0.4064)
			(stroke
				(width 0.1524)
				(type default)
			)
			(layer "F.SilkS")
		)
		(fp_line
			(start 0.7874 0.4064)
			(end -0.7874 0.4064)
			(stroke
				(width 0.1524)
				(type default)
			)
			(layer "F.SilkS")
		)
		(fp_line
			(start -0.7874 -0.4064)
			(end 0.7874 -0.4064)
			(stroke
				(width 0.1524)
				(type default)
			)
			(layer "F.SilkS")
		)
		(fp_line
			(start 0.7874 -0.4064)
			(end 0.7874 0.4064)
			(stroke
				(width 0.1524)
				(type default)
			)
			(layer "F.SilkS")
		)
		(fp_line
			(start -0.67945 0.3048)
			(end -0.67945 -0.305054)
			(stroke
				(width 0.1)
				(type default)
			)
			(layer "F.Fab")
		)
		(fp_line
			(start -0.12065 0.3048)
			(end -0.67945 0.3048)
			(stroke
				(width 0.1)
				(type default)
			)
			(layer "F.Fab")
		)
		(fp_line
			(start 0.120396 0.3048)
			(end 0.120396 0.2794)
			(stroke
				(width 0.1)
				(type default)
			)
			(layer "F.Fab")
		)
		(fp_line
			(start 0.67945 0.3048)
			(end 0.120396 0.3048)
			(stroke
				(width 0.1)
				(type default)
			)
			(layer "F.Fab")
		)
		(fp_line
			(start -0.12065 0.2794)
			(end -0.12065 0.3048)
			(stroke
				(width 0.1)
				(type default)
			)
			(layer "F.Fab")
		)
		(fp_line
			(start 0.120396 0.2794)
			(end -0.12065 0.2794)
			(stroke
				(width 0.1)
				(type default)
			)
			(layer "F.Fab")
		)
		(fp_line
			(start -0.12065 -0.2794)
			(end 0.12065 -0.2794)
			(stroke
				(width 0.1)
				(type default)
			)
			(layer "F.Fab")
		)
		(fp_line
			(start 0.12065 -0.2794)
			(end 0.12065 -0.3048)
			(stroke
				(width 0.1)
				(type default)
			)
			(layer "F.Fab")
		)
		(fp_line
			(start 0.12065 -0.3048)
			(end 0.67945 -0.3048)
			(stroke
				(width 0.1)
				(type default)
			)
			(layer "F.Fab")
		)
		(fp_line
			(start 0.67945 -0.3048)
			(end 0.67945 0.3048)
			(stroke
				(width 0.1)
				(type default)
			)
			(layer "F.Fab")
		)
		(fp_line
			(start -0.67945 -0.305054)
			(end -0.12065 -0.305054)
			(stroke
				(width 0.1)
				(type default)
			)
			(layer "F.Fab")
		)
		(fp_line
			(start -0.12065 -0.305054)
			(end -0.12065 -0.2794)
			(stroke
				(width 0.1)
				(type default)
			)
			(layer "F.Fab")
		)
		(pad "1" smd circle
			(at -0.40005 0 270)
			(size 0 0)
			(layers "F.Cu" "F.Mask" "F.Paste")
			(net "RST_RT_CPU1_P2_PERST_R_N")
		)
		(pad "2" smd circle
			(at 0.40005 0 270)
			(size 0 0)
			(layers "F.Cu" "F.Mask" "F.Paste")
			(net "RST_RT_CPU1_P2_PERST_R2_N")
		)
	)
	(footprint ""
		(layer "F.Cu")
		(at 346.987876 -70.098412 90)
		(property "Reference" "D85"
			(at -3.934714 -0.691642 90)
			(unlocked yes)
			(layer "F.SilkS")
			(effects
				(font
					(size 0.7874 0.5842)
					(thickness 0.1524)
				)
				(justify left)
			)
		)
		(property "Value" ""
			(at 0 0 90)
			(layer "F.Fab")
			(effects
				(font
					(size 1.27 1.27)
				)
			)
		)
		(duplicate_pad_numbers_are_jumpers no)
		(fp_line
			(start 1.16078 -0.4826)
			(end 1.16078 0.4826)
			(stroke
				(width 0.1524)
				(type default)
			)
			(layer "F.SilkS")
		)
		(fp_line
			(start 1.03378 -0.4826)
			(end 1.03378 0.4826)
			(stroke
				(width 0.1524)
				(type default)
			)
			(layer "F.SilkS")
		)
		(fp_line
			(start 0.90678 -0.4826)
			(end 0.90678 0.4826)
			(stroke
				(width 0.1524)
				(type default)
			)
			(layer "F.SilkS")
		)
		(fp_line
			(start -0.64008 -0.4826)
			(end 1.16078 -0.4826)
			(stroke
				(width 0.1524)
				(type default)
			)
			(layer "F.SilkS")
		)
		(fp_line
			(start -0.79248 -0.4826)
			(end 1.03378 -0.4826)
			(stroke
				(width 0.1524)
				(type default)
			)
			(layer "F.SilkS")
		)
		(fp_line
			(start -0.89408 -0.4826)
			(end 0.90678 -0.4826)
			(stroke
				(width 0.1524)
				(type default)
			)
			(layer "F.SilkS")
		)
		(fp_line
			(start 1.16078 0.4826)
			(end -0.64008 0.4826)
			(stroke
				(width 0.1524)
				(type default)
			)
			(layer "F.SilkS")
		)
		(fp_line
			(start 1.03378 0.4826)
			(end -0.79248 0.4826)
			(stroke
				(width 0.1524)
				(type default)
			)
			(layer "F.SilkS")
		)
		(fp_line
			(start 0.90678 0.4826)
			(end -0.90678 0.4826)
			(stroke
				(width 0.1524)
				(type default)
			)
			(layer "F.SilkS")
		)
		(fp_line
			(start -0.90678 0.4826)
			(end -0.90678 -0.4699)
			(stroke
				(width 0.1524)
				(type default)
			)
			(layer "F.SilkS")
		)
		(fp_line
			(start 0.499872 -0.249936)
			(end 0.499872 0.249936)
			(stroke
				(width 0.1)
				(type default)
			)
			(layer "F.Fab")
		)
		(fp_line
			(start -0.499872 -0.249936)
			(end 0.499872 -0.249936)
			(stroke
				(width 0.1)
				(type default)
			)
			(layer "F.Fab")
		)
		(fp_line
			(start 0.499872 0.249936)
			(end -0.499872 0.249936)
			(stroke
				(width 0.1)
				(type default)
			)
			(layer "F.Fab")
		)
		(fp_line
			(start -0.499872 0.249936)
			(end -0.499872 -0.249936)
			(stroke
				(width 0.1)
				(type default)
			)
			(layer "F.Fab")
		)
		(pad "A" smd rect
			(at -0.47498 0 90)
			(size 0.6096 0.7112)
			(layers "F.Cu" "F.Mask" "F.Paste")
			(net "LED_PWRGD_PVDD18_S5_P1_R")
		)
		(pad "C" smd rect
			(at 0.47498 0 90)
			(size 0.6096 0.7112)
			(layers "F.Cu" "F.Mask" "F.Paste")
			(net "LED_PWRGD_PVDD18_S5_P1_D")
		)
	)
	(footprint ""
		(layer "F.Cu")
		(at 108.355892 -259.845302)
		(property "Reference" "C2127"
			(at 0 0 0)
			(layer "F.SilkS")
			(hide yes)
			(effects
				(font
					(size 1.27 1.27)
				)
			)
		)
		(property "Value" ""
			(at 0 0 0)
			(layer "F.Fab")
			(effects
				(font
					(size 1.27 1.27)
				)
			)
		)
		(duplicate_pad_numbers_are_jumpers no)
		(fp_line
			(start -0.7874 -0.4064)
			(end 0.7874 -0.4064)
			(stroke
				(width 0.1524)
				(type default)
			)
			(layer "F.SilkS")
		)
		(fp_line
			(start -0.7874 0.4064)
			(end -0.7874 -0.4064)
			(stroke
				(width 0.1524)
				(type default)
			)
			(layer "F.SilkS")
		)
		(fp_line
			(start 0.7874 -0.4064)
			(end 0.7874 0.4064)
			(stroke
				(width 0.1524)
				(type default)
			)
			(layer "F.SilkS")
		)
		(fp_line
			(start 0.7874 0.4064)
			(end -0.7874 0.4064)
			(stroke
				(width 0.1524)
				(type default)
			)
			(layer "F.SilkS")
		)
		(fp_line
			(start -0.67945 -0.305054)
			(end -0.12065 -0.305054)
			(stroke
				(width 0.1)
				(type default)
			)
			(layer "F.Fab")
		)
		(fp_line
			(start -0.67945 0.3048)
			(end -0.67945 -0.305054)
			(stroke
				(width 0.1)
				(type default)
			)
			(layer "F.Fab")
		)
		(fp_line
			(start -0.12065 -0.305054)
			(end -0.12065 -0.2794)
			(stroke
				(width 0.1)
				(type default)
			)
			(layer "F.Fab")
		)
		(fp_line
			(start -0.12065 -0.2794)
			(end 0.12065 -0.2794)
			(stroke
				(width 0.1)
				(type default)
			)
			(layer "F.Fab")
		)
		(fp_line
			(start -0.12065 0.2794)
			(end -0.12065 0.3048)
			(stroke
				(width 0.1)
				(type default)
			)
			(layer "F.Fab")
		)
		(fp_line
			(start -0.12065 0.3048)
			(end -0.67945 0.3048)
			(stroke
				(width 0.1)
				(type default)
			)
			(layer "F.Fab")
		)
		(fp_line
			(start 0.120396 0.2794)
			(end -0.12065 0.2794)
			(stroke
				(width 0.1)
				(type default)
			)
			(layer "F.Fab")
		)
		(fp_line
			(start 0.120396 0.3048)
			(end 0.120396 0.2794)
			(stroke
				(width 0.1)
				(type default)
			)
			(layer "F.Fab")
		)
		(fp_line
			(start 0.12065 -0.3048)
			(end 0.67945 -0.3048)
			(stroke
				(width 0.1)
				(type default)
			)
			(layer "F.Fab")
		)
		(fp_line
			(start 0.12065 -0.2794)
			(end 0.12065 -0.3048)
			(stroke
				(width 0.1)
				(type default)
			)
			(layer "F.Fab")
		)
		(fp_line
			(start 0.67945 -0.3048)
			(end 0.67945 0.3048)
			(stroke
				(width 0.1)
				(type default)
			)
			(layer "F.Fab")
		)
		(fp_line
			(start 0.67945 0.3048)
			(end 0.120396 0.3048)
			(stroke
				(width 0.1)
				(type default)
			)
			(layer "F.Fab")
		)
		(pad "1" smd circle
			(at -0.40005 0)
			(size 0 0)
			(layers "F.Cu" "F.Mask" "F.Paste")
			(net "PVDDIO_P1")
		)
		(pad "2" smd circle
			(at 0.40005 0)
			(size 0 0)
			(layers "F.Cu" "F.Mask" "F.Paste")
			(net "GND")
		)
	)
)
